#ISCELL
  pure_quanta quanta_title_block_c *
  *
#ISCELL
  standard offpage *
  page253_i1
#CELL
  pure_quanta q_res *
  page253_i10
#CELL
  pure_quanta q_res *
  page253_i11
#CELL
  pure_quanta q_res *
  page253_i12
#ISCELL
  standard offpage *
  page253_i13
#ISCELL
  standard offpage *
  page253_i14
#ISCELL
  standard offpage *
  page253_i15
#ISCELL
  standard offpage *
  page253_i16
#ISCELL
  standard offpage *
  page253_i17
#ISCELL
  standard offpage *
  page253_i18
#ISCELL
  standard offpage *
  page253_i19
#ISCELL
  standard offpage *
  page253_i2
#ISCELL
  standard offpage *
  page253_i20
#ISCELL
  standard offpage *
  page253_i21
#ISCELL
  standard offpage *
  page253_i22
#CELL
  pure_quanta q_res *
  page253_i23
#CELL
  pure_quanta q_res *
  page253_i24
#CELL
  pure_quanta q_res *
  page253_i25
#CELL
  pure_quanta q_res *
  page253_i26
#CELL
  pure_quanta q_res *
  page253_i27
#CELL
  pure_quanta q_res *
  page253_i28
#ISCELL
  standard offpage *
  page253_i29
#CELL
  pure_quanta q_res *
  page253_i3
#ISCELL
  standard offpage *
  page253_i30
#ISCELL
  standard offpage *
  page253_i31
#ISCELL
  standard offpage *
  page253_i32
#ISCELL
  standard offpage *
  page253_i33
#ISCELL
  standard offpage *
  page253_i34
#CELL
  pure_quanta q_res *
  page253_i4
#CELL
  pure_quanta q_res *
  page253_i5
#CELL
  pure_quanta q_res *
  page253_i6
#CELL
  pure_quanta q_res *
  page253_i7
#CELL
  pure_quanta q_res *
  page253_i8
#CELL
  pure_quanta q_res *
  page253_i9
